# S9S_MB_2U (Grand Teton) — schematic netlist excerpt (pin names and nets, part order shuffled) for the footprints in the layout excerpt that follows; sources: Cadence DE-HDL packaged netlist, KiCad conversion of 03242023_DA0F0TMBIJ0_F0T_Motherboard_J_brd_V01_OCP.brd

PC386  Q_CAP  0.1UF 25V 10% X7R  pkg 0402  page 296 : A = PVCCD_HV_CPU1_ISENSE_P ; B = GND
PR1310  Q_RES  11.3K 0.1% CHIP  pkg 0402LF  page 281 : A = PVPP_HBM_CPU0_FB ; B = SH_PVPP_HBM_CPU0_N

(kicad_pcb
	(version 20260206)
	(generator "pcbnew")
	(generator_version "10.0")
	(general
		(thickness 1.6)
		(legacy_teardrops no)
	)
	(paper "A4")
	(title_block
		(title "03242023_DA0F0TMBIJ0_F0T_Motherboard_J_brd_V01_OCP.brd")
		(comment 1 "Grand Teton / footprints 1881-1882 of 6105")
	)
	(layers
		(0 "F.Cu" signal "TOP")
		(4 "In1.Cu" signal "GND")
		(6 "In2.Cu" signal "IN1")
		(8 "In3.Cu" signal "GND1")
		(10 "In4.Cu" signal "IN2")
		(12 "In5.Cu" signal "GND2")
		(14 "In6.Cu" signal "IN3")
		(16 "In7.Cu" signal "GND3")
		(18 "In8.Cu" signal "VCC")
		(20 "In9.Cu" signal "VCC1")
		(22 "In10.Cu" signal "GND4")
		(24 "In11.Cu" signal "IN4")
		(26 "In12.Cu" signal "GND5")
		(28 "In13.Cu" signal "IN5")
		(30 "In14.Cu" signal "GND6")
		(32 "In15.Cu" signal "IN6")
		(34 "In16.Cu" signal "GND7")
		(2 "B.Cu" signal "BOTTOM")
		(9 "F.Adhes" user "F.Adhesive")
		(11 "B.Adhes" user "B.Adhesive")
		(13 "F.Paste" user "Package Geometry/Pastemask Top")
		(15 "B.Paste" user "Package Geometry/Pastemask Bottom")
		(5 "F.SilkS" user "Ref Des/Silkscreen Top")
		(7 "B.SilkS" user "Ref Des/Silkscreen Bottom")
		(1 "F.Mask" user "Board Geometry/Soldermask Top")
		(3 "B.Mask" user "Board Geometry/Soldermask Bottom")
		(17 "Dwgs.User" user "User.Drawings")
		(19 "Cmts.User" user "User.Comments")
		(21 "Eco1.User" user "User.Eco1")
		(23 "Eco2.User" user "User.Eco2")
		(25 "Edge.Cuts" user "Board Geometry/Outline")
		(27 "Margin" user)
		(31 "F.CrtYd" user "Package Geometry/Place Bound Top")
		(29 "B.CrtYd" user "Package Geometry/Place Bound Bottom")
		(35 "F.Fab" user "Ref Des/Assembly Top")
		(33 "B.Fab" user "Ref Des/Assembly Bottom")
	)
	(footprint ""
		(layer "F.Cu")
		(at 32.191452 -165.761162)
		(property "Reference" "PC386"
			(at 0 0 0)
			(layer "F.SilkS")
			(hide yes)
			(effects
				(font
					(size 1.27 1.27)
				)
			)
		)
		(property "Value" ""
			(at 0 0 0)
			(layer "F.Fab")
			(effects
				(font
					(size 1.27 1.27)
				)
			)
		)
		(duplicate_pad_numbers_are_jumpers no)
		(fp_line
			(start -0.7874 -0.4064)
			(end 0.7874 -0.4064)
			(stroke
				(width 0.1524)
				(type default)
			)
			(layer "F.SilkS")
		)
		(fp_line
			(start -0.7874 0.4064)
			(end -0.7874 -0.4064)
			(stroke
				(width 0.1524)
				(type default)
			)
			(layer "F.SilkS")
		)
		(fp_line
			(start 0.7874 -0.4064)
			(end 0.7874 0.4064)
			(stroke
				(width 0.1524)
				(type default)
			)
			(layer "F.SilkS")
		)
		(fp_line
			(start 0.7874 0.4064)
			(end -0.7874 0.4064)
			(stroke
				(width 0.1524)
				(type default)
			)
			(layer "F.SilkS")
		)
		(fp_line
			(start -0.67945 -0.305054)
			(end -0.12065 -0.305054)
			(stroke
				(width 0.1)
				(type default)
			)
			(layer "F.Fab")
		)
		(fp_line
			(start -0.67945 0.3048)
			(end -0.67945 -0.305054)
			(stroke
				(width 0.1)
				(type default)
			)
			(layer "F.Fab")
		)
		(fp_line
			(start -0.12065 -0.305054)
			(end -0.12065 -0.2794)
			(stroke
				(width 0.1)
				(type default)
			)
			(layer "F.Fab")
		)
		(fp_line
			(start -0.12065 -0.2794)
			(end 0.12065 -0.2794)
			(stroke
				(width 0.1)
				(type default)
			)
			(layer "F.Fab")
		)
		(fp_line
			(start -0.12065 0.2794)
			(end -0.12065 0.3048)
			(stroke
				(width 0.1)
				(type default)
			)
			(layer "F.Fab")
		)
		(fp_line
			(start -0.12065 0.3048)
			(end -0.67945 0.3048)
			(stroke
				(width 0.1)
				(type default)
			)
			(layer "F.Fab")
		)
		(fp_line
			(start 0.120396 0.2794)
			(end -0.12065 0.2794)
			(stroke
				(width 0.1)
				(type default)
			)
			(layer "F.Fab")
		)
		(fp_line
			(start 0.120396 0.3048)
			(end 0.120396 0.2794)
			(stroke
				(width 0.1)
				(type default)
			)
			(layer "F.Fab")
		)
		(fp_line
			(start 0.12065 -0.3048)
			(end 0.67945 -0.3048)
			(stroke
				(width 0.1)
				(type default)
			)
			(layer "F.Fab")
		)
		(fp_line
			(start 0.12065 -0.2794)
			(end 0.12065 -0.3048)
			(stroke
				(width 0.1)
				(type default)
			)
			(layer "F.Fab")
		)
		(fp_line
			(start 0.67945 -0.3048)
			(end 0.67945 0.3048)
			(stroke
				(width 0.1)
				(type default)
			)
			(layer "F.Fab")
		)
		(fp_line
			(start 0.67945 0.3048)
			(end 0.120396 0.3048)
			(stroke
				(width 0.1)
				(type default)
			)
			(layer "F.Fab")
		)
		(pad "1" smd circle
			(at -0.40005 0)
			(size 0 0)
			(layers "F.Cu" "F.Mask" "F.Paste")
			(net "PVCCD_HV_CPU1_ISENSE_P")
		)
		(pad "2" smd circle
			(at 0.40005 0)
			(size 0 0)
			(layers "F.Cu" "F.Mask" "F.Paste")
			(net "GND")
		)
	)
	(footprint ""
		(layer "F.Cu")
		(at 370.232686 -357.11638 90)
		(property "Reference" "PR1310"
			(at 0 0 90)
			(layer "F.SilkS")
			(hide yes)
			(effects
				(font
					(size 1.27 1.27)
				)
			)
		)
		(property "Value" ""
			(at 0 0 90)
			(layer "F.Fab")
			(effects
				(font
					(size 1.27 1.27)
				)
			)
		)
		(duplicate_pad_numbers_are_jumpers no)
		(fp_line
			(start 0.7874 -0.4064)
			(end 0.7874 0.4064)
			(stroke
				(width 0.1524)
				(type default)
			)
			(layer "F.SilkS")
		)
		(fp_line
			(start -0.7874 -0.4064)
			(end 0.7874 -0.4064)
			(stroke
				(width 0.1524)
				(type default)
			)
			(layer "F.SilkS")
		)
		(fp_line
			(start 0.7874 0.4064)
			(end -0.7874 0.4064)
			(stroke
				(width 0.1524)
				(type default)
			)
			(layer "F.SilkS")
		)
		(fp_line
			(start -0.7874 0.4064)
			(end -0.7874 -0.4064)
			(stroke
				(width 0.1524)
				(type default)
			)
			(layer "F.SilkS")
		)
		(fp_line
			(start -0.12065 -0.305054)
			(end -0.12065 -0.2794)
			(stroke
				(width 0.1)
				(type default)
			)
			(layer "F.Fab")
		)
		(fp_line
			(start -0.67945 -0.305054)
			(end -0.12065 -0.305054)
			(stroke
				(width 0.1)
				(type default)
			)
			(layer "F.Fab")
		)
		(fp_line
			(start 0.67945 -0.3048)
			(end 0.67945 0.3048)
			(stroke
				(width 0.1)
				(type default)
			)
			(layer "F.Fab")
		)
		(fp_line
			(start 0.12065 -0.3048)
			(end 0.67945 -0.3048)
			(stroke
				(width 0.1)
				(type default)
			)
			(layer "F.Fab")
		)
		(fp_line
			(start 0.12065 -0.2794)
			(end 0.12065 -0.3048)
			(stroke
				(width 0.1)
				(type default)
			)
			(layer "F.Fab")
		)
		(fp_line
			(start -0.12065 -0.2794)
			(end 0.12065 -0.2794)
			(stroke
				(width 0.1)
				(type default)
			)
			(layer "F.Fab")
		)
		(fp_line
			(start 0.120396 0.2794)
			(end -0.12065 0.2794)
			(stroke
				(width 0.1)
				(type default)
			)
			(layer "F.Fab")
		)
		(fp_line
			(start -0.12065 0.2794)
			(end -0.12065 0.3048)
			(stroke
				(width 0.1)
				(type default)
			)
			(layer "F.Fab")
		)
		(fp_line
			(start 0.67945 0.3048)
			(end 0.120396 0.3048)
			(stroke
				(width 0.1)
				(type default)
			)
			(layer "F.Fab")
		)
		(fp_line
			(start 0.120396 0.3048)
			(end 0.120396 0.2794)
			(stroke
				(width 0.1)
				(type default)
			)
			(layer "F.Fab")
		)
		(fp_line
			(start -0.12065 0.3048)
			(end -0.67945 0.3048)
			(stroke
				(width 0.1)
				(type default)
			)
			(layer "F.Fab")
		)
		(fp_line
			(start -0.67945 0.3048)
			(end -0.67945 -0.305054)
			(stroke
				(width 0.1)
				(type default)
			)
			(layer "F.Fab")
		)
		(pad "1" smd circle
			(at -0.40005 0 90)
			(size 0 0)
			(layers "F.Cu" "F.Mask" "F.Paste")
			(net "PVPP_HBM_CPU0_FB")
		)
		(pad "2" smd circle
			(at 0.40005 0 90)
			(size 0 0)
			(layers "F.Cu" "F.Mask" "F.Paste")
			(net "SH_PVPP_HBM_CPU0_N")
		)
	)
)
